# S9S_MB_2U (Grand Teton) — schematic netlist excerpt (pin names and nets, part order shuffled) for the footprints in the layout excerpt that follows; sources: Cadence DE-HDL packaged netlist, KiCad conversion of 03242023_DA0F0TMBIJ0_F0T_Motherboard_J_brd_V01_OCP.brd

PC525_P1_4  Q_CAP  2.2UF 10V 10% X6S  pkg C0402  page 286 : A = PVCCIN_CPU1_PVCC ; B = GND

Q84  MOSFET_NCH_DUAL  PJT138K IC  pkg SOT363XD  page 254
  S1  = GND
  G1  = PWRGD_PVCCD_HV_CPU1
  D2  = LED_PWRGD_PVPP_HBM_CPU1_D
  S2  = GND
  G2  = PWRGD_PVPP_HBM_CPU1
  D1  = LED_PWRGD_PVCCD_HV_CPU1_D

(kicad_pcb
	(version 20260206)
	(generator "pcbnew")
	(generator_version "10.0")
	(general
		(thickness 1.6)
		(legacy_teardrops no)
	)
	(paper "A4")
	(title_block
		(title "03242023_DA0F0TMBIJ0_F0T_Motherboard_J_brd_V01_OCP.brd")
		(comment 1 "Grand Teton / footprints 3071-3072 of 6105")
	)
	(layers
		(0 "F.Cu" signal "TOP")
		(4 "In1.Cu" signal "GND")
		(6 "In2.Cu" signal "IN1")
		(8 "In3.Cu" signal "GND1")
		(10 "In4.Cu" signal "IN2")
		(12 "In5.Cu" signal "GND2")
		(14 "In6.Cu" signal "IN3")
		(16 "In7.Cu" signal "GND3")
		(18 "In8.Cu" signal "VCC")
		(20 "In9.Cu" signal "VCC1")
		(22 "In10.Cu" signal "GND4")
		(24 "In11.Cu" signal "IN4")
		(26 "In12.Cu" signal "GND5")
		(28 "In13.Cu" signal "IN5")
		(30 "In14.Cu" signal "GND6")
		(32 "In15.Cu" signal "IN6")
		(34 "In16.Cu" signal "GND7")
		(2 "B.Cu" signal "BOTTOM")
		(9 "F.Adhes" user "F.Adhesive")
		(11 "B.Adhes" user "B.Adhesive")
		(13 "F.Paste" user "Package Geometry/Pastemask Top")
		(15 "B.Paste" user "Package Geometry/Pastemask Bottom")
		(5 "F.SilkS" user "Ref Des/Silkscreen Top")
		(7 "B.SilkS" user "Ref Des/Silkscreen Bottom")
		(1 "F.Mask" user "Board Geometry/Soldermask Top")
		(3 "B.Mask" user "Board Geometry/Soldermask Bottom")
		(17 "Dwgs.User" user "User.Drawings")
		(19 "Cmts.User" user "User.Comments")
		(21 "Eco1.User" user "User.Eco1")
		(23 "Eco2.User" user "User.Eco2")
		(25 "Edge.Cuts" user "Board Geometry/Outline")
		(27 "Margin" user)
		(31 "F.CrtYd" user "Package Geometry/Place Bound Top")
		(29 "B.CrtYd" user "Package Geometry/Place Bound Bottom")
		(35 "F.Fab" user "Ref Des/Assembly Top")
		(33 "B.Fab" user "Ref Des/Assembly Bottom")
	)
	(footprint ""
		(layer "F.Cu")
		(at 117.904514 -333.525368 -90)
		(property "Reference" "PC525_P1_4"
			(at 0 0 270)
			(layer "F.SilkS")
			(hide yes)
			(effects
				(font
					(size 1.27 1.27)
				)
			)
		)
		(property "Value" ""
			(at 0 0 270)
			(layer "F.Fab")
			(effects
				(font
					(size 1.27 1.27)
				)
			)
		)
		(duplicate_pad_numbers_are_jumpers no)
		(fp_line
			(start -0.7874 0.4064)
			(end -0.7874 -0.4064)
			(stroke
				(width 0.1524)
				(type default)
			)
			(layer "F.SilkS")
		)
		(fp_line
			(start 0.7874 0.4064)
			(end -0.7874 0.4064)
			(stroke
				(width 0.1524)
				(type default)
			)
			(layer "F.SilkS")
		)
		(fp_line
			(start -0.7874 -0.4064)
			(end 0.7874 -0.4064)
			(stroke
				(width 0.1524)
				(type default)
			)
			(layer "F.SilkS")
		)
		(fp_line
			(start 0.7874 -0.4064)
			(end 0.7874 0.4064)
			(stroke
				(width 0.1524)
				(type default)
			)
			(layer "F.SilkS")
		)
		(fp_line
			(start -0.67945 0.3048)
			(end -0.67945 -0.305054)
			(stroke
				(width 0.1)
				(type default)
			)
			(layer "F.Fab")
		)
		(fp_line
			(start -0.12065 0.3048)
			(end -0.67945 0.3048)
			(stroke
				(width 0.1)
				(type default)
			)
			(layer "F.Fab")
		)
		(fp_line
			(start 0.120396 0.3048)
			(end 0.120396 0.2794)
			(stroke
				(width 0.1)
				(type default)
			)
			(layer "F.Fab")
		)
		(fp_line
			(start 0.67945 0.3048)
			(end 0.120396 0.3048)
			(stroke
				(width 0.1)
				(type default)
			)
			(layer "F.Fab")
		)
		(fp_line
			(start -0.12065 0.2794)
			(end -0.12065 0.3048)
			(stroke
				(width 0.1)
				(type default)
			)
			(layer "F.Fab")
		)
		(fp_line
			(start 0.120396 0.2794)
			(end -0.12065 0.2794)
			(stroke
				(width 0.1)
				(type default)
			)
			(layer "F.Fab")
		)
		(fp_line
			(start -0.12065 -0.2794)
			(end 0.12065 -0.2794)
			(stroke
				(width 0.1)
				(type default)
			)
			(layer "F.Fab")
		)
		(fp_line
			(start 0.12065 -0.2794)
			(end 0.12065 -0.3048)
			(stroke
				(width 0.1)
				(type default)
			)
			(layer "F.Fab")
		)
		(fp_line
			(start 0.12065 -0.3048)
			(end 0.67945 -0.3048)
			(stroke
				(width 0.1)
				(type default)
			)
			(layer "F.Fab")
		)
		(fp_line
			(start 0.67945 -0.3048)
			(end 0.67945 0.3048)
			(stroke
				(width 0.1)
				(type default)
			)
			(layer "F.Fab")
		)
		(fp_line
			(start -0.67945 -0.305054)
			(end -0.12065 -0.305054)
			(stroke
				(width 0.1)
				(type default)
			)
			(layer "F.Fab")
		)
		(fp_line
			(start -0.12065 -0.305054)
			(end -0.12065 -0.2794)
			(stroke
				(width 0.1)
				(type default)
			)
			(layer "F.Fab")
		)
		(pad "1" smd circle
			(at -0.40005 0 270)
			(size 0 0)
			(layers "F.Cu" "F.Mask" "F.Paste")
			(net "PVCCIN_CPU1_PVCC")
		)
		(pad "2" smd circle
			(at 0.40005 0 270)
			(size 0 0)
			(layers "F.Cu" "F.Mask" "F.Paste")
			(net "GND")
		)
	)
	(footprint ""
		(layer "F.Cu")
		(at 94.086426 -99.577398)
		(property "Reference" "Q84"
			(at -4.72948 -0.638048 0)
			(unlocked yes)
			(layer "F.SilkS")
			(effects
				(font
					(size 0.7874 0.5842)
					(thickness 0.1524)
				)
				(justify left)
			)
		)
		(property "Value" ""
			(at 0 0 0)
			(layer "F.Fab")
			(effects
				(font
					(size 1.27 1.27)
				)
			)
		)
		(duplicate_pad_numbers_are_jumpers no)
		(fp_line
			(start -1.332738 -1.100074)
			(end -0.4826 -1.100074)
			(stroke
				(width 0.1524)
				(type default)
			)
			(layer "F.SilkS")
		)
		(fp_line
			(start -1.332738 1.100074)
			(end -1.332738 -1.100074)
			(stroke
				(width 0.1524)
				(type default)
			)
			(layer "F.SilkS")
		)
		(fp_line
			(start -0.4826 -1.100074)
			(end 0 -0.541274)
			(stroke
				(width 0.1524)
				(type default)
			)
			(layer "F.SilkS")
		)
		(fp_line
			(start 0 -0.541274)
			(end 0.4826 -1.100074)
			(stroke
				(width 0.1524)
				(type default)
			)
			(layer "F.SilkS")
		)
		(fp_line
			(start 0.4826 -1.100074)
			(end 1.332738 -1.100074)
			(stroke
				(width 0.1524)
				(type default)
			)
			(layer "F.SilkS")
		)
		(fp_line
			(start 1.332738 -1.100074)
			(end 1.332738 1.100074)
			(stroke
				(width 0.1524)
				(type default)
			)
			(layer "F.SilkS")
		)
		(fp_line
			(start 1.332738 1.100074)
			(end -1.332738 1.100074)
			(stroke
				(width 0.1524)
				(type default)
			)
			(layer "F.SilkS")
		)
		(fp_poly
			(pts
				(xy -2.32918 -1.036574) (xy -1.627124 -0.685546) (xy -2.32918 -0.334518)
			)
			(stroke
				(width 0)
				(type default)
			)
			(fill yes)
			(layer "F.SilkS")
		)
		(fp_line
			(start -0.674878 -1.100074)
			(end 0.674878 -1.100074)
			(stroke
				(width 0.1)
				(type default)
			)
			(layer "F.Fab")
		)
		(fp_line
			(start -0.674878 1.100074)
			(end -0.674878 -1.100074)
			(stroke
				(width 0.1)
				(type default)
			)
			(layer "F.Fab")
		)
		(fp_line
			(start 0.674878 -1.100074)
			(end 0.674878 1.100074)
			(stroke
				(width 0.1)
				(type default)
			)
			(layer "F.Fab")
		)
		(fp_line
			(start 0.674878 1.100074)
			(end -0.674878 1.100074)
			(stroke
				(width 0.1)
				(type default)
			)
			(layer "F.Fab")
		)
		(fp_poly
			(pts
				(xy -2.2352 -0.298958) (xy -2.2352 -1.001014) (xy -1.533144 -0.649986)
			)
			(stroke
				(width 0)
				(type default)
			)
			(fill yes)
			(layer "F.Fab")
		)
		(pad "1" smd rect
			(at -0.94996 -0.649986 90)
			(size 0.4318 0.508)
			(layers "F.Cu" "F.Mask" "F.Paste")
			(net "GND")
		)
		(pad "2" smd rect
			(at -0.94996 0 90)
			(size 0.4318 0.508)
			(layers "F.Cu" "F.Mask" "F.Paste")
			(net "PWRGD_PVCCD_HV_CPU1")
		)
		(pad "3" smd rect
			(at -0.94996 0.649986 90)
			(size 0.4318 0.508)
			(layers "F.Cu" "F.Mask" "F.Paste")
			(net "LED_PWRGD_PVPP_HBM_CPU1_D")
		)
		(pad "4" smd rect
			(at 0.94996 0.649986 90)
			(size 0.4318 0.508)
			(layers "F.Cu" "F.Mask" "F.Paste")
			(net "GND")
		)
		(pad "5" smd rect
			(at 0.94996 0 90)
			(size 0.4318 0.508)
			(layers "F.Cu" "F.Mask" "F.Paste")
			(net "PWRGD_PVPP_HBM_CPU1")
		)
		(pad "6" smd rect
			(at 0.94996 -0.649986 90)
			(size 0.4318 0.508)
			(layers "F.Cu" "F.Mask" "F.Paste")
			(net "LED_PWRGD_PVCCD_HV_CPU1_D")
		)
	)
)
